# SCM (Grand Teton) — schematic netlist excerpt (pin names and nets, part order shuffled) for the footprints in the layout excerpt that follows; sources: Cadence DE-HDL packaged netlist, KiCad conversion of 12092022_DA0F0TMDCD0_F0T_Management_Board_D_brd_V3_OCP.brd

R563  Q_RES  4.7K 1% CHIP  pkg 0402LF  page 25 : A = P3V3_AUX ; B = RST_SPI_FLASH_BUF_N
C313  Q_CAP  0.1UF 25V 10% X7R  pkg 0402  page 25 : A = P3V3_AUX ; B = GND

(kicad_pcb
	(version 20260206)
	(generator "pcbnew")
	(generator_version "10.0")
	(general
		(thickness 1.6)
		(legacy_teardrops no)
	)
	(paper "A4")
	(title_block
		(title "12092022_DA0F0TMDCD0_F0T_Management_Board_D_brd_V3_OCP.brd")
		(comment 1 "Grand Teton / footprints 701-702 of 1440")
	)
	(layers
		(0 "F.Cu" signal "TOP")
		(4 "In1.Cu" signal "GND")
		(6 "In2.Cu" signal "IN1")
		(8 "In3.Cu" signal "GND1")
		(10 "In4.Cu" signal "IN2")
		(12 "In5.Cu" signal "VCC")
		(14 "In6.Cu" signal "VCC1")
		(16 "In7.Cu" signal "IN3")
		(18 "In8.Cu" signal "GND2")
		(20 "In9.Cu" signal "IN4")
		(22 "In10.Cu" signal "GND3")
		(2 "B.Cu" signal "BOTTOM")
		(9 "F.Adhes" user "F.Adhesive")
		(11 "B.Adhes" user "B.Adhesive")
		(13 "F.Paste" user "Package Geometry/Pastemask Top")
		(15 "B.Paste" user "Package Geometry/Pastemask Bottom")
		(5 "F.SilkS" user "Ref Des/Silkscreen Top")
		(7 "B.SilkS" user "Ref Des/Silkscreen Bottom")
		(1 "F.Mask" user "Board Geometry/Soldermask Top")
		(3 "B.Mask" user "Board Geometry/Soldermask Bottom")
		(17 "Dwgs.User" user "User.Drawings")
		(19 "Cmts.User" user "User.Comments")
		(21 "Eco1.User" user "User.Eco1")
		(23 "Eco2.User" user "User.Eco2")
		(25 "Edge.Cuts" user "Board Geometry/Outline")
		(27 "Margin" user)
		(31 "F.CrtYd" user "Package Geometry/Place Bound Top")
		(29 "B.CrtYd" user "Package Geometry/Place Bound Bottom")
		(35 "F.Fab" user "Ref Des/Assembly Top")
		(33 "B.Fab" user "Ref Des/Assembly Bottom")
	)
	(footprint ""
		(layer "F.Cu")
		(at 48.4378 -79.0194 180)
		(property "Reference" "C313"
			(at 0 0 180)
			(layer "F.SilkS")
			(hide yes)
			(effects
				(font
					(size 1.27 1.27)
				)
			)
		)
		(property "Value" ""
			(at 0 0 180)
			(layer "F.Fab")
			(effects
				(font
					(size 1.27 1.27)
				)
			)
		)
		(duplicate_pad_numbers_are_jumpers no)
		(fp_line
			(start 0.7874 0.4064)
			(end -0.7874 0.4064)
			(stroke
				(width 0.1524)
				(type default)
			)
			(layer "F.SilkS")
		)
		(fp_line
			(start 0.7874 -0.4064)
			(end 0.7874 0.4064)
			(stroke
				(width 0.1524)
				(type default)
			)
			(layer "F.SilkS")
		)
		(fp_line
			(start -0.7874 0.4064)
			(end -0.7874 -0.4064)
			(stroke
				(width 0.1524)
				(type default)
			)
			(layer "F.SilkS")
		)
		(fp_line
			(start -0.7874 -0.4064)
			(end 0.7874 -0.4064)
			(stroke
				(width 0.1524)
				(type default)
			)
			(layer "F.SilkS")
		)
		(fp_line
			(start 0.67945 0.3048)
			(end 0.120396 0.3048)
			(stroke
				(width 0.1)
				(type default)
			)
			(layer "F.Fab")
		)
		(fp_line
			(start 0.67945 -0.3048)
			(end 0.67945 0.3048)
			(stroke
				(width 0.1)
				(type default)
			)
			(layer "F.Fab")
		)
		(fp_line
			(start 0.12065 -0.2794)
			(end 0.12065 -0.3048)
			(stroke
				(width 0.1)
				(type default)
			)
			(layer "F.Fab")
		)
		(fp_line
			(start 0.12065 -0.3048)
			(end 0.67945 -0.3048)
			(stroke
				(width 0.1)
				(type default)
			)
			(layer "F.Fab")
		)
		(fp_line
			(start 0.120396 0.3048)
			(end 0.120396 0.2794)
			(stroke
				(width 0.1)
				(type default)
			)
			(layer "F.Fab")
		)
		(fp_line
			(start 0.120396 0.2794)
			(end -0.12065 0.2794)
			(stroke
				(width 0.1)
				(type default)
			)
			(layer "F.Fab")
		)
		(fp_line
			(start -0.12065 0.3048)
			(end -0.67945 0.3048)
			(stroke
				(width 0.1)
				(type default)
			)
			(layer "F.Fab")
		)
		(fp_line
			(start -0.12065 0.2794)
			(end -0.12065 0.3048)
			(stroke
				(width 0.1)
				(type default)
			)
			(layer "F.Fab")
		)
		(fp_line
			(start -0.12065 -0.2794)
			(end 0.12065 -0.2794)
			(stroke
				(width 0.1)
				(type default)
			)
			(layer "F.Fab")
		)
		(fp_line
			(start -0.12065 -0.305054)
			(end -0.12065 -0.2794)
			(stroke
				(width 0.1)
				(type default)
			)
			(layer "F.Fab")
		)
		(fp_line
			(start -0.67945 0.3048)
			(end -0.67945 -0.305054)
			(stroke
				(width 0.1)
				(type default)
			)
			(layer "F.Fab")
		)
		(fp_line
			(start -0.67945 -0.305054)
			(end -0.12065 -0.305054)
			(stroke
				(width 0.1)
				(type default)
			)
			(layer "F.Fab")
		)
		(pad "1" smd circle
			(at -0.40005 0 180)
			(size 0 0)
			(layers "F.Cu" "F.Mask" "F.Paste")
			(net "P3V3_AUX")
		)
		(pad "2" smd circle
			(at 0.40005 0 180)
			(size 0 0)
			(layers "F.Cu" "F.Mask" "F.Paste")
			(net "GND")
		)
	)
	(footprint ""
		(layer "F.Cu")
		(at 18.4912 -46.3042 -90)
		(property "Reference" "R563"
			(at 0 0 270)
			(layer "F.SilkS")
			(hide yes)
			(effects
				(font
					(size 1.27 1.27)
				)
			)
		)
		(property "Value" ""
			(at 0 0 270)
			(layer "F.Fab")
			(effects
				(font
					(size 1.27 1.27)
				)
			)
		)
		(duplicate_pad_numbers_are_jumpers no)
		(fp_line
			(start -0.7874 0.4064)
			(end -0.7874 -0.4064)
			(stroke
				(width 0.1524)
				(type default)
			)
			(layer "F.SilkS")
		)
		(fp_line
			(start 0.7874 0.4064)
			(end -0.7874 0.4064)
			(stroke
				(width 0.1524)
				(type default)
			)
			(layer "F.SilkS")
		)
		(fp_line
			(start -0.7874 -0.4064)
			(end 0.7874 -0.4064)
			(stroke
				(width 0.1524)
				(type default)
			)
			(layer "F.SilkS")
		)
		(fp_line
			(start 0.7874 -0.4064)
			(end 0.7874 0.4064)
			(stroke
				(width 0.1524)
				(type default)
			)
			(layer "F.SilkS")
		)
		(fp_line
			(start -0.67945 0.3048)
			(end -0.67945 -0.305054)
			(stroke
				(width 0.1)
				(type default)
			)
			(layer "F.Fab")
		)
		(fp_line
			(start -0.12065 0.3048)
			(end -0.67945 0.3048)
			(stroke
				(width 0.1)
				(type default)
			)
			(layer "F.Fab")
		)
		(fp_line
			(start 0.120396 0.3048)
			(end 0.120396 0.2794)
			(stroke
				(width 0.1)
				(type default)
			)
			(layer "F.Fab")
		)
		(fp_line
			(start 0.67945 0.3048)
			(end 0.120396 0.3048)
			(stroke
				(width 0.1)
				(type default)
			)
			(layer "F.Fab")
		)
		(fp_line
			(start -0.12065 0.2794)
			(end -0.12065 0.3048)
			(stroke
				(width 0.1)
				(type default)
			)
			(layer "F.Fab")
		)
		(fp_line
			(start 0.120396 0.2794)
			(end -0.12065 0.2794)
			(stroke
				(width 0.1)
				(type default)
			)
			(layer "F.Fab")
		)
		(fp_line
			(start -0.12065 -0.2794)
			(end 0.12065 -0.2794)
			(stroke
				(width 0.1)
				(type default)
			)
			(layer "F.Fab")
		)
		(fp_line
			(start 0.12065 -0.2794)
			(end 0.12065 -0.3048)
			(stroke
				(width 0.1)
				(type default)
			)
			(layer "F.Fab")
		)
		(fp_line
			(start 0.12065 -0.3048)
			(end 0.67945 -0.3048)
			(stroke
				(width 0.1)
				(type default)
			)
			(layer "F.Fab")
		)
		(fp_line
			(start 0.67945 -0.3048)
			(end 0.67945 0.3048)
			(stroke
				(width 0.1)
				(type default)
			)
			(layer "F.Fab")
		)
		(fp_line
			(start -0.67945 -0.305054)
			(end -0.12065 -0.305054)
			(stroke
				(width 0.1)
				(type default)
			)
			(layer "F.Fab")
		)
		(fp_line
			(start -0.12065 -0.305054)
			(end -0.12065 -0.2794)
			(stroke
				(width 0.1)
				(type default)
			)
			(layer "F.Fab")
		)
		(pad "1" smd circle
			(at -0.40005 0 270)
			(size 0 0)
			(layers "F.Cu" "F.Mask" "F.Paste")
			(net "P3V3_AUX")
		)
		(pad "2" smd circle
			(at 0.40005 0 270)
			(size 0 0)
			(layers "F.Cu" "F.Mask" "F.Paste")
			(net "RST_SPI_FLASH_BUF_N")
		)
	)
)
